#ISCELL
  logical_power cad_note *
  *
#ISCELL
  logical_power design_note *
  *
#ISCELL
  pure_quanta quanta_title_block_c *
  *
#CELL
  pure_quanta q_res *
  page172_i10
#CELL
  pure_quanta emmitsburg_rev0p9 *
  page172_i11
#ISCELL
  standard offpage *
  page172_i12
#ISCELL
  standard offpage *
  page172_i13
#ISCELL
  standard offpage *
  page172_i20
#ISCELL
  standard offpage *
  page172_i21
#ISCELL
  standard offpage *
  page172_i24
#ISCELL
  standard offpage *
  page172_i25
#ISCELL
  standard offpage *
  page172_i32
#ISCELL
  standard offpage *
  page172_i33
#ISCELL
  standard offpage *
  page172_i34
#ISCELL
  standard offpage *
  page172_i35
#ISCELL
  logical_power universal_gnd *
  page172_i9
